(kicad_pcb
	(version 20260206)
	(generator "pcbnew")
	(generator_version "10.0")
	(general
		(thickness 1.6)
		(legacy_teardrops no)
	)
	(paper "A4")
	(title_block
		(title "timecard-production-celestica-r4006 — R4006-B0001-02_R01.brd")
		(comment 1 "Time Appliance Project (Time Card) / footprints 703-707 of 1113")
	)
	(layers
		(0 "F.Cu" signal "TOP")
		(4 "In1.Cu" signal "L02_GND1")
		(6 "In2.Cu" signal "L03_SIG1")
		(8 "In3.Cu" signal "L04_GND2")
		(10 "In4.Cu" signal "L05_VCC1")
		(12 "In5.Cu" signal "L06_VCC2")
		(14 "In6.Cu" signal "L07_GND3")
		(16 "In7.Cu" signal "L08_SIG2")
		(18 "In8.Cu" signal "L09_GND4")
		(2 "B.Cu" signal "BOTTOM")
		(9 "F.Adhes" user "F.Adhesive")
		(11 "B.Adhes" user "B.Adhesive")
		(13 "F.Paste" user "Package Geometry/Pastemask Top")
		(15 "B.Paste" user "Package Geometry/Pastemask Bottom")
		(5 "F.SilkS" user "Ref Des/Silkscreen Top")
		(7 "B.SilkS" user "Ref Des/Silkscreen Bottom")
		(1 "F.Mask" user "Board Geometry/Soldermask Top")
		(3 "B.Mask" user "Board Geometry/Soldermask Bottom")
		(17 "Dwgs.User" user "User.Drawings")
		(19 "Cmts.User" user "User.Comments")
		(21 "Eco1.User" user "User.Eco1")
		(23 "Eco2.User" user "User.Eco2")
		(25 "Edge.Cuts" user "Board Geometry/Outline")
		(27 "Margin" user)
		(31 "F.CrtYd" user "Package Geometry/Place Bound Top")
		(29 "B.CrtYd" user "Package Geometry/Place Bound Bottom")
		(35 "F.Fab" user "Ref Des/Assembly Top")
		(33 "B.Fab" user "Ref Des/Assembly Bottom")
	)
	(footprint ""
		(layer "B.Cu")
		(at 152.883108 -49.01311 90)
		(property "Reference" "R300"
			(at 3.94589 -0.649478 270)
			(unlocked yes)
			(layer "B.SilkS")
			(effects
				(font
					(size 0.7874 0.5842)
					(thickness 0.1524)
				)
				(justify mirror)
			)
		)
		(property "Value" "VAL*"
			(at -0.02032 2.13233 90)
			(unlocked yes)
			(layer "B.Fab")
			(hide yes)
			(effects
				(font
					(size 0.7874 0.5842)
					(thickness 0.1524)
				)
				(justify mirror)
			)
		)
		(property "Device Type" "RESISTOR-G155-14701-01,4.7KOHMA"
			(at -0.008382 1.210564 90)
			(unlocked yes)
			(layer "B.Fab")
			(hide yes)
			(effects
				(font
					(size 0.7874 0.5842)
					(thickness 0.1524)
				)
				(justify mirror)
			)
		)
		(property "User Part Number" "PARTNUM*"
			(at -0.02032 4.024884 90)
			(unlocked yes)
			(layer "Cmts.User")
			(hide yes)
			(effects
				(font
					(size 0.7874 0.5842)
					(thickness 0.1524)
				)
				(justify mirror)
			)
		)
		(property "Tolerance" "TOL*"
			(at -0.044704 3.05435 90)
			(unlocked yes)
			(layer "Cmts.User")
			(hide yes)
			(effects
				(font
					(size 0.7874 0.5842)
					(thickness 0.1524)
				)
				(justify mirror)
			)
		)
		(duplicate_pad_numbers_are_jumpers no)
		(fp_line
			(start 1.143 -0.5588)
			(end 1.143 0.5588)
			(stroke
				(width 0.1)
				(type default)
			)
			(layer "B.SilkS")
		)
		(fp_line
			(start -1.143 -0.5588)
			(end 1.143 -0.5588)
			(stroke
				(width 0.1)
				(type default)
			)
			(layer "B.SilkS")
		)
		(fp_line
			(start 1.143 0.5588)
			(end -1.143 0.5588)
			(stroke
				(width 0.1)
				(type default)
			)
			(layer "B.SilkS")
		)
		(fp_line
			(start -1.143 0.5588)
			(end -1.143 -0.5588)
			(stroke
				(width 0.1)
				(type default)
			)
			(layer "B.SilkS")
		)
		(fp_rect
			(start 1.143 0.5588)
			(end -1.143 -0.5588)
			(stroke
				(width 0)
				(type default)
			)
			(fill no)
			(layer "B.CrtYd")
		)
		(fp_line
			(start 0.508 -0.3048)
			(end 0.508 0.3048)
			(stroke
				(width 0.1)
				(type default)
			)
			(layer "B.Fab")
		)
		(fp_line
			(start -0.508 -0.3048)
			(end 0.508 -0.3048)
			(stroke
				(width 0.1)
				(type default)
			)
			(layer "B.Fab")
		)
		(fp_line
			(start 0.508 0.3048)
			(end -0.508 0.3048)
			(stroke
				(width 0.1)
				(type default)
			)
			(layer "B.Fab")
		)
		(fp_line
			(start -0.508 0.3048)
			(end -0.508 -0.3048)
			(stroke
				(width 0.1)
				(type default)
			)
			(layer "B.Fab")
		)
		(pad "1" smd rect
			(at 0.5334 0 270)
			(size 0.7112 0.6096)
			(layers "B.Cu" "B.Mask" "B.Paste")
			(net "XP3R3V_FPGA")
		)
		(pad "2" smd rect
			(at -0.5334 0 270)
			(size 0.7112 0.6096)
			(layers "B.Cu" "B.Mask" "B.Paste")
			(net "FPGA_IN_SHT3X_ALERT_N")
		)
		(zone
			(layer "B.Cu")
			(hatch none 0.5)
			(connect_pads
				(clearance 0)
			)
			(min_thickness 0.25)
			(keepout
				(tracks allowed)
				(vias not_allowed)
				(pads allowed)
				(copperpour not_allowed)
				(footprints allowed)
			)
			(placement
				(enabled no)
				(sheetname "")
			)
			(fill
				(thermal_gap 0.5)
				(thermal_bridge_width 0.5)
				(island_removal_mode 0)
			)
			(polygon
				(pts
					(xy 153.187908 -49.08931) (xy 152.578308 -49.08931) (xy 152.578308 -48.93691) (xy 153.187908 -48.93691)
				)
			)
		)
	)
	(footprint ""
		(layer "B.Cu")
		(at 105.847134 -40.323008 90)
		(property "Reference" "C121"
			(at -1.143508 -41.383204 270)
			(unlocked yes)
			(layer "B.SilkS")
			(effects
				(font
					(size 0.635 0.4064)
					(thickness 0.1524)
				)
				(justify mirror)
			)
		)
		(property "Value" "VAL*"
			(at 0 3.718306 90)
			(unlocked yes)
			(layer "B.Fab")
			(hide yes)
			(effects
				(font
					(size 0.7874 0.5842)
					(thickness 0.127)
				)
				(justify mirror)
			)
		)
		(property "Device Type" "CAPACITOR-G105-0B104-CK,0.1UF,A"
			(at 0 1.432306 90)
			(unlocked yes)
			(layer "B.Fab")
			(hide yes)
			(effects
				(font
					(size 0.7874 0.5842)
					(thickness 0.127)
				)
				(justify mirror)
			)
		)
		(property "User Part Number" "PARTNUM*"
			(at 0 2.575306 90)
			(unlocked yes)
			(layer "Cmts.User")
			(hide yes)
			(effects
				(font
					(size 0.7874 0.5842)
					(thickness 0.127)
				)
				(justify mirror)
			)
		)
		(property "Tolerance" "TOL*"
			(at 0 4.861306 90)
			(unlocked yes)
			(layer "Cmts.User")
			(hide yes)
			(effects
				(font
					(size 0.7874 0.5842)
					(thickness 0.127)
				)
				(justify mirror)
			)
		)
		(duplicate_pad_numbers_are_jumpers no)
		(fp_line
			(start 0.970026 -0.4699)
			(end -0.970026 -0.4699)
			(stroke
				(width 0.1)
				(type default)
			)
			(layer "B.SilkS")
		)
		(fp_line
			(start -0.970026 -0.4699)
			(end -0.970026 0.4699)
			(stroke
				(width 0.1)
				(type default)
			)
			(layer "B.SilkS")
		)
		(fp_line
			(start 0.970026 0.4699)
			(end 0.970026 -0.4699)
			(stroke
				(width 0.1)
				(type default)
			)
			(layer "B.SilkS")
		)
		(fp_line
			(start -0.970026 0.4699)
			(end 0.970026 0.4699)
			(stroke
				(width 0.1)
				(type default)
			)
			(layer "B.SilkS")
		)
		(fp_poly
			(pts
				(xy 0.970026 0.4699) (xy -0.970026 0.4699) (xy -0.970026 -0.4699) (xy 0.970026 -0.4699)
			)
			(stroke
				(width 0)
				(type default)
			)
			(fill no)
			(layer "B.CrtYd")
		)
		(fp_line
			(start 0.508 -0.3048)
			(end -0.508 -0.3048)
			(stroke
				(width 0.1)
				(type default)
			)
			(layer "B.Fab")
		)
		(fp_line
			(start -0.508 -0.3048)
			(end -0.508 0.3048)
			(stroke
				(width 0.1)
				(type default)
			)
			(layer "B.Fab")
		)
		(fp_line
			(start 0.508 0.3048)
			(end 0.508 -0.3048)
			(stroke
				(width 0.1)
				(type default)
			)
			(layer "B.Fab")
		)
		(fp_line
			(start -0.508 0.3048)
			(end 0.508 0.3048)
			(stroke
				(width 0.1)
				(type default)
			)
			(layer "B.Fab")
		)
		(pad "1" smd circle
			(at 0.500126 0 270)
			(size 0.635 0.635)
			(layers "B.Cu" "B.Mask" "B.Paste")
			(net "XP1R0V_FPGA_VCCINT")
		)
		(pad "2" smd circle
			(at -0.500126 0 270)
			(size 0.635 0.635)
			(layers "B.Cu" "B.Mask" "B.Paste")
			(net "SG")
		)
	)
	(footprint ""
		(layer "B.Cu")
		(at 162.56 -25.908 180)
		(property "Reference" "R415"
			(at 0.508 2.62763 0)
			(unlocked yes)
			(layer "B.SilkS")
			(effects
				(font
					(size 0.7874 0.5842)
					(thickness 0.1524)
				)
				(justify mirror)
			)
		)
		(property "Value" "VAL*"
			(at -0.02032 2.13233 180)
			(unlocked yes)
			(layer "B.Fab")
			(hide yes)
			(effects
				(font
					(size 0.7874 0.5842)
					(thickness 0.1524)
				)
				(justify mirror)
			)
		)
		(property "Tolerance" "TOL*"
			(at -0.044704 3.05435 180)
			(unlocked yes)
			(layer "Cmts.User")
			(hide yes)
			(effects
				(font
					(size 0.7874 0.5842)
					(thickness 0.1524)
				)
				(justify mirror)
			)
		)
		(property "User Part Number" "PARTNUM*"
			(at -0.02032 4.024884 180)
			(unlocked yes)
			(layer "Cmts.User")
			(hide yes)
			(effects
				(font
					(size 0.7874 0.5842)
					(thickness 0.1524)
				)
				(justify mirror)
			)
		)
		(property "Device Type" "RESISTOR-G155-11001-01,1KOHM,1%"
			(at -0.008382 1.210564 180)
			(unlocked yes)
			(layer "B.Fab")
			(hide yes)
			(effects
				(font
					(size 0.7874 0.5842)
					(thickness 0.1524)
				)
				(justify mirror)
			)
		)
		(duplicate_pad_numbers_are_jumpers no)
		(fp_line
			(start 1.143 0.5588)
			(end -1.143 0.5588)
			(stroke
				(width 0.1)
				(type default)
			)
			(layer "B.SilkS")
		)
		(fp_line
			(start 1.143 -0.5588)
			(end 1.143 0.5588)
			(stroke
				(width 0.1)
				(type default)
			)
			(layer "B.SilkS")
		)
		(fp_line
			(start -1.143 0.5588)
			(end -1.143 -0.5588)
			(stroke
				(width 0.1)
				(type default)
			)
			(layer "B.SilkS")
		)
		(fp_line
			(start -1.143 -0.5588)
			(end 1.143 -0.5588)
			(stroke
				(width 0.1)
				(type default)
			)
			(layer "B.SilkS")
		)
		(fp_rect
			(start 1.143 -0.5588)
			(end -1.143 0.5588)
			(stroke
				(width 0)
				(type default)
			)
			(fill no)
			(layer "B.CrtYd")
		)
		(fp_line
			(start 0.508 0.3048)
			(end -0.508 0.3048)
			(stroke
				(width 0.1)
				(type default)
			)
			(layer "B.Fab")
		)
		(fp_line
			(start 0.508 -0.3048)
			(end 0.508 0.3048)
			(stroke
				(width 0.1)
				(type default)
			)
			(layer "B.Fab")
		)
		(fp_line
			(start -0.508 0.3048)
			(end -0.508 -0.3048)
			(stroke
				(width 0.1)
				(type default)
			)
			(layer "B.Fab")
		)
		(fp_line
			(start -0.508 -0.3048)
			(end 0.508 -0.3048)
			(stroke
				(width 0.1)
				(type default)
			)
			(layer "B.Fab")
		)
		(pad "1" smd rect
			(at 0.5334 0)
			(size 0.7112 0.6096)
			(layers "B.Cu" "B.Mask" "B.Paste")
			(net "UNNAMED_6_LM75BDPTSSOP8_I81_A1")
		)
		(pad "2" smd rect
			(at -0.5334 0)
			(size 0.7112 0.6096)
			(layers "B.Cu" "B.Mask" "B.Paste")
			(net "SG")
		)
		(zone
			(layer "B.Cu")
			(hatch none 0.5)
			(connect_pads
				(clearance 0)
			)
			(min_thickness 0.25)
			(keepout
				(tracks allowed)
				(vias not_allowed)
				(pads allowed)
				(copperpour not_allowed)
				(footprints allowed)
			)
			(placement
				(enabled no)
				(sheetname "")
			)
			(fill
				(thermal_gap 0.5)
				(thermal_bridge_width 0.5)
				(island_removal_mode 0)
			)
			(polygon
				(pts
					(xy 162.4838 -25.6032) (xy 162.6362 -25.6032) (xy 162.6362 -26.2128) (xy 162.4838 -26.2128)
				)
			)
		)
		(zone
			(layer "B.Cu")
			(hatch none 0.5)
			(connect_pads
				(clearance 0)
			)
			(min_thickness 0.25)
			(keepout
				(tracks not_allowed)
				(vias allowed)
				(pads allowed)
				(copperpour not_allowed)
				(footprints allowed)
			)
			(placement
				(enabled no)
				(sheetname "")
			)
			(fill
				(thermal_gap 0.5)
				(thermal_bridge_width 0.5)
				(island_removal_mode 0)
			)
			(polygon
				(pts
					(xy 162.4838 -25.6032) (xy 162.6362 -25.6032) (xy 162.6362 -26.2128) (xy 162.4838 -26.2128)
				)
			)
		)
	)
	(footprint ""
		(layer "B.Cu")
		(at 156.083 -104.521 90)
		(property "Reference" "R169"
			(at -1.27 1.23063 270)
			(unlocked yes)
			(layer "B.SilkS")
			(effects
				(font
					(size 0.7874 0.5842)
					(thickness 0.1524)
				)
				(justify mirror)
			)
		)
		(property "Value" "VAL*"
			(at -0.02032 2.13233 90)
			(unlocked yes)
			(layer "B.Fab")
			(hide yes)
			(effects
				(font
					(size 0.7874 0.5842)
					(thickness 0.1524)
				)
				(justify mirror)
			)
		)
		(property "Tolerance" "TOL*"
			(at -0.044704 3.05435 90)
			(unlocked yes)
			(layer "Cmts.User")
			(hide yes)
			(effects
				(font
					(size 0.7874 0.5842)
					(thickness 0.1524)
				)
				(justify mirror)
			)
		)
		(property "User Part Number" "PARTNUM*"
			(at -0.02032 4.024884 90)
			(unlocked yes)
			(layer "Cmts.User")
			(hide yes)
			(effects
				(font
					(size 0.7874 0.5842)
					(thickness 0.1524)
				)
				(justify mirror)
			)
		)
		(property "Device Type" "RESISTOR-G155-13300-01,330OHM,A"
			(at -0.008382 1.210564 90)
			(unlocked yes)
			(layer "B.Fab")
			(hide yes)
			(effects
				(font
					(size 0.7874 0.5842)
					(thickness 0.1524)
				)
				(justify mirror)
			)
		)
		(duplicate_pad_numbers_are_jumpers no)
		(fp_line
			(start 1.143 -0.5588)
			(end 1.143 0.5588)
			(stroke
				(width 0.1)
				(type default)
			)
			(layer "B.SilkS")
		)
		(fp_line
			(start -1.143 -0.5588)
			(end 1.143 -0.5588)
			(stroke
				(width 0.1)
				(type default)
			)
			(layer "B.SilkS")
		)
		(fp_line
			(start 1.143 0.5588)
			(end -1.143 0.5588)
			(stroke
				(width 0.1)
				(type default)
			)
			(layer "B.SilkS")
		)
		(fp_line
			(start -1.143 0.5588)
			(end -1.143 -0.5588)
			(stroke
				(width 0.1)
				(type default)
			)
			(layer "B.SilkS")
		)
		(fp_rect
			(start -1.143 0.5588)
			(end 1.143 -0.5588)
			(stroke
				(width 0)
				(type default)
			)
			(fill no)
			(layer "B.CrtYd")
		)
		(fp_line
			(start 0.508 -0.3048)
			(end 0.508 0.3048)
			(stroke
				(width 0.1)
				(type default)
			)
			(layer "B.Fab")
		)
		(fp_line
			(start -0.508 -0.3048)
			(end 0.508 -0.3048)
			(stroke
				(width 0.1)
				(type default)
			)
			(layer "B.Fab")
		)
		(fp_line
			(start 0.508 0.3048)
			(end -0.508 0.3048)
			(stroke
				(width 0.1)
				(type default)
			)
			(layer "B.Fab")
		)
		(fp_line
			(start -0.508 0.3048)
			(end -0.508 -0.3048)
			(stroke
				(width 0.1)
				(type default)
			)
			(layer "B.Fab")
		)
		(pad "1" smd rect
			(at 0.5334 0 270)
			(size 0.7112 0.6096)
			(layers "B.Cu" "B.Mask" "B.Paste")
			(net "UNNAMED_14_OPTICAL_I289_A")
		)
		(pad "2" smd rect
			(at -0.5334 0 270)
			(size 0.7112 0.6096)
			(layers "B.Cu" "B.Mask" "B.Paste")
			(net "XP3R3V_FT4232")
		)
		(zone
			(layer "B.Cu")
			(hatch none 0.5)
			(connect_pads
				(clearance 0)
			)
			(min_thickness 0.25)
			(keepout
				(tracks allowed)
				(vias not_allowed)
				(pads allowed)
				(copperpour not_allowed)
				(footprints allowed)
			)
			(placement
				(enabled no)
				(sheetname "")
			)
			(fill
				(thermal_gap 0.5)
				(thermal_bridge_width 0.5)
				(island_removal_mode 0)
			)
			(polygon
				(pts
					(xy 156.3878 -104.4448) (xy 156.3878 -104.5972) (xy 155.7782 -104.5972) (xy 155.7782 -104.4448)
				)
			)
		)
	)
	(footprint ""
		(layer "B.Cu")
		(at 33.77438 -17.9832)
		(property "Reference" "R176"
			(at 3.18262 1.25857 0)
			(unlocked yes)
			(layer "B.SilkS")
			(effects
				(font
					(size 0.7874 0.5842)
					(thickness 0.1524)
				)
				(justify mirror)
			)
		)
		(property "Value" "VAL*"
			(at -0.02032 2.13233 0)
			(unlocked yes)
			(layer "B.Fab")
			(hide yes)
			(effects
				(font
					(size 0.7874 0.5842)
					(thickness 0.1524)
				)
				(justify mirror)
			)
		)
		(property "Tolerance" "TOL*"
			(at -0.044704 3.05435 0)
			(unlocked yes)
			(layer "Cmts.User")
			(hide yes)
			(effects
				(font
					(size 0.7874 0.5842)
					(thickness 0.1524)
				)
				(justify mirror)
			)
		)
		(property "User Part Number" "PARTNUM*"
			(at -0.02032 4.024884 0)
			(unlocked yes)
			(layer "Cmts.User")
			(hide yes)
			(effects
				(font
					(size 0.7874 0.5842)
					(thickness 0.1524)
				)
				(justify mirror)
			)
		)
		(property "Device Type" "RESISTOR-G155-133R0-01,33OHM,1%"
			(at -0.008382 1.210564 0)
			(unlocked yes)
			(layer "B.Fab")
			(hide yes)
			(effects
				(font
					(size 0.7874 0.5842)
					(thickness 0.1524)
				)
				(justify mirror)
			)
		)
		(duplicate_pad_numbers_are_jumpers no)
		(fp_line
			(start -1.143 -0.5588)
			(end 1.143 -0.5588)
			(stroke
				(width 0.1)
				(type default)
			)
			(layer "B.SilkS")
		)
		(fp_line
			(start -1.143 0.5588)
			(end -1.143 -0.5588)
			(stroke
				(width 0.1)
				(type default)
			)
			(layer "B.SilkS")
		)
		(fp_line
			(start 1.143 -0.5588)
			(end 1.143 0.5588)
			(stroke
				(width 0.1)
				(type default)
			)
			(layer "B.SilkS")
		)
		(fp_line
			(start 1.143 0.5588)
			(end -1.143 0.5588)
			(stroke
				(width 0.1)
				(type default)
			)
			(layer "B.SilkS")
		)
		(fp_rect
			(start -1.143 0.5588)
			(end 1.143 -0.5588)
			(stroke
				(width 0)
				(type default)
			)
			(fill no)
			(layer "B.CrtYd")
		)
		(fp_line
			(start -0.508 -0.3048)
			(end 0.508 -0.3048)
			(stroke
				(width 0.1)
				(type default)
			)
			(layer "B.Fab")
		)
		(fp_line
			(start -0.508 0.3048)
			(end -0.508 -0.3048)
			(stroke
				(width 0.1)
				(type default)
			)
			(layer "B.Fab")
		)
		(fp_line
			(start 0.508 -0.3048)
			(end 0.508 0.3048)
			(stroke
				(width 0.1)
				(type default)
			)
			(layer "B.Fab")
		)
		(fp_line
			(start 0.508 0.3048)
			(end -0.508 0.3048)
			(stroke
				(width 0.1)
				(type default)
			)
			(layer "B.Fab")
		)
		(pad "1" smd rect
			(at 0.5334 0 180)
			(size 0.7112 0.6096)
			(layers "B.Cu" "B.Mask" "B.Paste")
			(net "PCIE_SMCLK")
		)
		(pad "2" smd rect
			(at -0.5334 0 180)
			(size 0.7112 0.6096)
			(layers "B.Cu" "B.Mask" "B.Paste")
			(net "EEPROM_SCL")
		)
		(zone
			(layer "B.Cu")
			(hatch none 0.5)
			(connect_pads
				(clearance 0)
			)
			(min_thickness 0.25)
			(keepout
				(tracks allowed)
				(vias not_allowed)
				(pads allowed)
				(copperpour not_allowed)
				(footprints allowed)
			)
			(placement
				(enabled no)
				(sheetname "")
			)
			(fill
				(thermal_gap 0.5)
				(thermal_bridge_width 0.5)
				(island_removal_mode 0)
			)
			(polygon
				(pts
					(xy 33.69818 -17.6784) (xy 33.85058 -17.6784) (xy 33.85058 -18.288) (xy 33.69818 -18.288)
				)
			)
		)
	)
)
